(kicad_pcb
	(version 20260206)
	(generator "pcbnew")
	(generator_version "10.0")
	(general
		(thickness 1.6)
		(legacy_teardrops no)
	)
	(paper "A4")
	(title_block
		(title "04192023_DAF0TMB3IC0_F0TG_MB_C_brd_V02_OCP.brd")
		(comment 1 "Grand Teton / footprints 799-801 of 8354")
	)
	(layers
		(0 "F.Cu" signal "TOP")
		(4 "In1.Cu" signal "GND")
		(6 "In2.Cu" signal "IN1")
		(8 "In3.Cu" signal "GND1")
		(10 "In4.Cu" signal "IN2")
		(12 "In5.Cu" signal "GND2")
		(14 "In6.Cu" signal "IN3")
		(16 "In7.Cu" signal "GND3")
		(18 "In8.Cu" signal "VCC")
		(20 "In9.Cu" signal "VCC1")
		(22 "In10.Cu" signal "GND4")
		(24 "In11.Cu" signal "IN4")
		(26 "In12.Cu" signal "GND5")
		(28 "In13.Cu" signal "IN5")
		(30 "In14.Cu" signal "GND6")
		(32 "In15.Cu" signal "IN6")
		(34 "In16.Cu" signal "GND7")
		(2 "B.Cu" signal "BOTTOM")
		(9 "F.Adhes" user "F.Adhesive")
		(11 "B.Adhes" user "B.Adhesive")
		(13 "F.Paste" user "Package Geometry/Pastemask Top")
		(15 "B.Paste" user "Package Geometry/Pastemask Bottom")
		(5 "F.SilkS" user "Ref Des/Silkscreen Top")
		(7 "B.SilkS" user "Ref Des/Silkscreen Bottom")
		(1 "F.Mask" user "Board Geometry/Soldermask Top")
		(3 "B.Mask" user "Board Geometry/Soldermask Bottom")
		(17 "Dwgs.User" user "User.Drawings")
		(19 "Cmts.User" user "User.Comments")
		(21 "Eco1.User" user "User.Eco1")
		(23 "Eco2.User" user "User.Eco2")
		(25 "Edge.Cuts" user "Board Geometry/Outline")
		(27 "Margin" user)
		(31 "F.CrtYd" user "Package Geometry/Place Bound Top")
		(29 "B.CrtYd" user "Package Geometry/Place Bound Bottom")
		(35 "F.Fab" user "Ref Des/Assembly Top")
		(33 "B.Fab" user "Ref Des/Assembly Bottom")
	)
	(footprint ""
		(layer "F.Cu")
		(at 353.900232 -259.355082)
		(property "Reference" "C2136"
			(at 0 0 0)
			(layer "F.SilkS")
			(hide yes)
			(effects
				(font
					(size 1.27 1.27)
				)
			)
		)
		(property "Value" ""
			(at 0 0 0)
			(layer "F.Fab")
			(effects
				(font
					(size 1.27 1.27)
				)
			)
		)
		(duplicate_pad_numbers_are_jumpers no)
		(fp_line
			(start -0.7874 -0.4064)
			(end 0.7874 -0.4064)
			(stroke
				(width 0.1524)
				(type default)
			)
			(layer "F.SilkS")
		)
		(fp_line
			(start -0.7874 0.4064)
			(end -0.7874 -0.4064)
			(stroke
				(width 0.1524)
				(type default)
			)
			(layer "F.SilkS")
		)
		(fp_line
			(start 0.7874 -0.4064)
			(end 0.7874 0.4064)
			(stroke
				(width 0.1524)
				(type default)
			)
			(layer "F.SilkS")
		)
		(fp_line
			(start 0.7874 0.4064)
			(end -0.7874 0.4064)
			(stroke
				(width 0.1524)
				(type default)
			)
			(layer "F.SilkS")
		)
		(fp_line
			(start -0.67945 -0.305054)
			(end -0.12065 -0.305054)
			(stroke
				(width 0.1)
				(type default)
			)
			(layer "F.Fab")
		)
		(fp_line
			(start -0.67945 0.3048)
			(end -0.67945 -0.305054)
			(stroke
				(width 0.1)
				(type default)
			)
			(layer "F.Fab")
		)
		(fp_line
			(start -0.12065 -0.305054)
			(end -0.12065 -0.2794)
			(stroke
				(width 0.1)
				(type default)
			)
			(layer "F.Fab")
		)
		(fp_line
			(start -0.12065 -0.2794)
			(end 0.12065 -0.2794)
			(stroke
				(width 0.1)
				(type default)
			)
			(layer "F.Fab")
		)
		(fp_line
			(start -0.12065 0.2794)
			(end -0.12065 0.3048)
			(stroke
				(width 0.1)
				(type default)
			)
			(layer "F.Fab")
		)
		(fp_line
			(start -0.12065 0.3048)
			(end -0.67945 0.3048)
			(stroke
				(width 0.1)
				(type default)
			)
			(layer "F.Fab")
		)
		(fp_line
			(start 0.120396 0.2794)
			(end -0.12065 0.2794)
			(stroke
				(width 0.1)
				(type default)
			)
			(layer "F.Fab")
		)
		(fp_line
			(start 0.120396 0.3048)
			(end 0.120396 0.2794)
			(stroke
				(width 0.1)
				(type default)
			)
			(layer "F.Fab")
		)
		(fp_line
			(start 0.12065 -0.3048)
			(end 0.67945 -0.3048)
			(stroke
				(width 0.1)
				(type default)
			)
			(layer "F.Fab")
		)
		(fp_line
			(start 0.12065 -0.2794)
			(end 0.12065 -0.3048)
			(stroke
				(width 0.1)
				(type default)
			)
			(layer "F.Fab")
		)
		(fp_line
			(start 0.67945 -0.3048)
			(end 0.67945 0.3048)
			(stroke
				(width 0.1)
				(type default)
			)
			(layer "F.Fab")
		)
		(fp_line
			(start 0.67945 0.3048)
			(end 0.120396 0.3048)
			(stroke
				(width 0.1)
				(type default)
			)
			(layer "F.Fab")
		)
		(pad "1" smd circle
			(at -0.40005 0)
			(size 0 0)
			(layers "F.Cu" "F.Mask" "F.Paste")
			(net "PVDDIO_P0")
		)
		(pad "2" smd circle
			(at 0.40005 0)
			(size 0 0)
			(layers "F.Cu" "F.Mask" "F.Paste")
			(net "GND")
		)
	)
	(footprint ""
		(layer "F.Cu")
		(at 322.837048 -43.573954 180)
		(property "Reference" "R3686"
			(at 0 0 180)
			(layer "F.SilkS")
			(hide yes)
			(effects
				(font
					(size 1.27 1.27)
				)
			)
		)
		(property "Value" ""
			(at 0 0 180)
			(layer "F.Fab")
			(effects
				(font
					(size 1.27 1.27)
				)
			)
		)
		(duplicate_pad_numbers_are_jumpers no)
		(fp_line
			(start 0.7874 0.4064)
			(end -0.7874 0.4064)
			(stroke
				(width 0.1524)
				(type default)
			)
			(layer "F.SilkS")
		)
		(fp_line
			(start 0.7874 -0.4064)
			(end 0.7874 0.4064)
			(stroke
				(width 0.1524)
				(type default)
			)
			(layer "F.SilkS")
		)
		(fp_line
			(start -0.7874 0.4064)
			(end -0.7874 -0.4064)
			(stroke
				(width 0.1524)
				(type default)
			)
			(layer "F.SilkS")
		)
		(fp_line
			(start -0.7874 -0.4064)
			(end 0.7874 -0.4064)
			(stroke
				(width 0.1524)
				(type default)
			)
			(layer "F.SilkS")
		)
		(fp_line
			(start 0.67945 0.3048)
			(end 0.120396 0.3048)
			(stroke
				(width 0.1)
				(type default)
			)
			(layer "F.Fab")
		)
		(fp_line
			(start 0.67945 -0.3048)
			(end 0.67945 0.3048)
			(stroke
				(width 0.1)
				(type default)
			)
			(layer "F.Fab")
		)
		(fp_line
			(start 0.12065 -0.2794)
			(end 0.12065 -0.3048)
			(stroke
				(width 0.1)
				(type default)
			)
			(layer "F.Fab")
		)
		(fp_line
			(start 0.12065 -0.3048)
			(end 0.67945 -0.3048)
			(stroke
				(width 0.1)
				(type default)
			)
			(layer "F.Fab")
		)
		(fp_line
			(start 0.120396 0.3048)
			(end 0.120396 0.2794)
			(stroke
				(width 0.1)
				(type default)
			)
			(layer "F.Fab")
		)
		(fp_line
			(start 0.120396 0.2794)
			(end -0.12065 0.2794)
			(stroke
				(width 0.1)
				(type default)
			)
			(layer "F.Fab")
		)
		(fp_line
			(start -0.12065 0.3048)
			(end -0.67945 0.3048)
			(stroke
				(width 0.1)
				(type default)
			)
			(layer "F.Fab")
		)
		(fp_line
			(start -0.12065 0.2794)
			(end -0.12065 0.3048)
			(stroke
				(width 0.1)
				(type default)
			)
			(layer "F.Fab")
		)
		(fp_line
			(start -0.12065 -0.2794)
			(end 0.12065 -0.2794)
			(stroke
				(width 0.1)
				(type default)
			)
			(layer "F.Fab")
		)
		(fp_line
			(start -0.12065 -0.305054)
			(end -0.12065 -0.2794)
			(stroke
				(width 0.1)
				(type default)
			)
			(layer "F.Fab")
		)
		(fp_line
			(start -0.67945 0.3048)
			(end -0.67945 -0.305054)
			(stroke
				(width 0.1)
				(type default)
			)
			(layer "F.Fab")
		)
		(fp_line
			(start -0.67945 -0.305054)
			(end -0.12065 -0.305054)
			(stroke
				(width 0.1)
				(type default)
			)
			(layer "F.Fab")
		)
		(pad "1" smd rect
			(at -0.40005 0)
			(size 0.4572 0.508)
			(layers "F.Cu" "F.Mask" "F.Paste")
			(net "P5V_ADC")
		)
		(pad "2" smd rect
			(at 0.40005 0)
			(size 0.4572 0.508)
			(layers "F.Cu" "F.Mask" "F.Paste")
			(net "P5V_ADC_TIC")
		)
	)
	(footprint ""
		(layer "F.Cu")
		(at 38.9128 -111.45774 180)
		(property "Reference" "R1474"
			(at 0 0 180)
			(layer "F.SilkS")
			(hide yes)
			(effects
				(font
					(size 1.27 1.27)
				)
			)
		)
		(property "Value" ""
			(at 0 0 180)
			(layer "F.Fab")
			(effects
				(font
					(size 1.27 1.27)
				)
			)
		)
		(duplicate_pad_numbers_are_jumpers no)
		(fp_line
			(start 0.7874 0.4064)
			(end -0.7874 0.4064)
			(stroke
				(width 0.1524)
				(type default)
			)
			(layer "F.SilkS")
		)
		(fp_line
			(start 0.7874 -0.4064)
			(end 0.7874 0.4064)
			(stroke
				(width 0.1524)
				(type default)
			)
			(layer "F.SilkS")
		)
		(fp_line
			(start -0.7874 0.4064)
			(end -0.7874 -0.4064)
			(stroke
				(width 0.1524)
				(type default)
			)
			(layer "F.SilkS")
		)
		(fp_line
			(start -0.7874 -0.4064)
			(end 0.7874 -0.4064)
			(stroke
				(width 0.1524)
				(type default)
			)
			(layer "F.SilkS")
		)
		(fp_line
			(start 0.67945 0.3048)
			(end 0.120396 0.3048)
			(stroke
				(width 0.1)
				(type default)
			)
			(layer "F.Fab")
		)
		(fp_line
			(start 0.67945 -0.3048)
			(end 0.67945 0.3048)
			(stroke
				(width 0.1)
				(type default)
			)
			(layer "F.Fab")
		)
		(fp_line
			(start 0.12065 -0.2794)
			(end 0.12065 -0.3048)
			(stroke
				(width 0.1)
				(type default)
			)
			(layer "F.Fab")
		)
		(fp_line
			(start 0.12065 -0.3048)
			(end 0.67945 -0.3048)
			(stroke
				(width 0.1)
				(type default)
			)
			(layer "F.Fab")
		)
		(fp_line
			(start 0.120396 0.3048)
			(end 0.120396 0.2794)
			(stroke
				(width 0.1)
				(type default)
			)
			(layer "F.Fab")
		)
		(fp_line
			(start 0.120396 0.2794)
			(end -0.12065 0.2794)
			(stroke
				(width 0.1)
				(type default)
			)
			(layer "F.Fab")
		)
		(fp_line
			(start -0.12065 0.3048)
			(end -0.67945 0.3048)
			(stroke
				(width 0.1)
				(type default)
			)
			(layer "F.Fab")
		)
		(fp_line
			(start -0.12065 0.2794)
			(end -0.12065 0.3048)
			(stroke
				(width 0.1)
				(type default)
			)
			(layer "F.Fab")
		)
		(fp_line
			(start -0.12065 -0.2794)
			(end 0.12065 -0.2794)
			(stroke
				(width 0.1)
				(type default)
			)
			(layer "F.Fab")
		)
		(fp_line
			(start -0.12065 -0.305054)
			(end -0.12065 -0.2794)
			(stroke
				(width 0.1)
				(type default)
			)
			(layer "F.Fab")
		)
		(fp_line
			(start -0.67945 0.3048)
			(end -0.67945 -0.305054)
			(stroke
				(width 0.1)
				(type default)
			)
			(layer "F.Fab")
		)
		(fp_line
			(start -0.67945 -0.305054)
			(end -0.12065 -0.305054)
			(stroke
				(width 0.1)
				(type default)
			)
			(layer "F.Fab")
		)
		(pad "1" smd circle
			(at -0.40005 0 180)
			(size 0 0)
			(layers "F.Cu" "F.Mask" "F.Paste")
			(net "P12V_AUX_DSC_G2")
		)
		(pad "2" smd circle
			(at 0.40005 0 180)
			(size 0 0)
			(layers "F.Cu" "F.Mask" "F.Paste")
			(net "GND")
		)
	)
)
